(kicad_pcb
	(version 20241229)
	(generator "pcbnew")
	(generator_version "9.0")
	(general
		(thickness 1.599998)
		(legacy_teardrops no)
	)
	(paper "A4")
	(title_block
		(title "Artix - Datacenter Secure Control Module (DC-SCM)")
		(date "2024-11-06")
		(rev "1.1.3")
		(comment 9 "footprints 87-92 of 544")
	)
	(layers
		(0 "F.Cu" signal)
		(4 "In1.Cu" signal)
		(6 "In2.Cu" signal)
		(8 "In3.Cu" signal)
		(10 "In4.Cu" signal)
		(12 "In5.Cu" signal)
		(14 "In6.Cu" signal)
		(2 "B.Cu" signal)
		(9 "F.Adhes" user "F.Adhesive")
		(11 "B.Adhes" user "B.Adhesive")
		(13 "F.Paste" user)
		(15 "B.Paste" user)
		(5 "F.SilkS" user "F.Silkscreen")
		(7 "B.SilkS" user "B.Silkscreen")
		(1 "F.Mask" user)
		(3 "B.Mask" user)
		(17 "Dwgs.User" user "User.Drawings")
		(19 "Cmts.User" user "User.Comments")
		(21 "Eco1.User" user "User.Eco1")
		(23 "Eco2.User" user "User.Eco2")
		(25 "Edge.Cuts" user)
		(27 "Margin" user)
		(31 "F.CrtYd" user "F.Courtyard")
		(29 "B.CrtYd" user "B.Courtyard")
		(35 "F.Fab" user)
		(33 "B.Fab" user)
	)
	(footprint "antmicro-footprints:C_0402_1005Metric"
		(layer "F.Cu")
		(at 93.674 140.075 -90)
		(descr "Capacitor SMD 0402")
		(tags "capacitor SMD 0402")
		(property "Reference" "C58"
			(at -2.975 -0.326 90)
			(layer "F.SilkS")
			(effects
				(font
					(size 0.7 0.7)
					(thickness 0.15)
				)
				(justify right bottom)
			)
		)
		(property "Value" "C_470n_0402"
			(at 0 1.4 90)
			(layer "F.Fab")
			(effects
				(font
					(size 0.7 0.7)
					(thickness 0.15)
				)
				(justify right bottom)
			)
		)
		(property "Datasheet" "https://product.tdk.com/en/search/capacitor/ceramic/mlcc/info?part_no=C1005X5R1E474M050BB"
			(at 0 0 270)
			(layer "F.Fab")
			(hide yes)
			(effects
				(font
					(size 1.27 1.27)
					(thickness 0.15)
				)
			)
		)
		(property "Description" "SMD Multilayer Ceramic Capacitor, 0.47 µF, 25 V, 0402 [1005 Metric], ± 20%, X5R, C"
			(at 0 0 270)
			(layer "F.Fab")
			(hide yes)
			(effects
				(font
					(size 1.27 1.27)
					(thickness 0.15)
				)
			)
		)
		(property "Author" "Antmicro"
			(at -46.401 233.749 0)
			(layer "F.Fab")
			(hide yes)
			(effects
				(font
					(size 1 1)
					(thickness 0.15)
				)
			)
		)
		(property "Dielectric" ""
			(at -46.401 233.749 0)
			(layer "F.Fab")
			(hide yes)
			(effects
				(font
					(size 1 1)
					(thickness 0.15)
				)
			)
		)
		(property "License" "Apache-2.0"
			(at -46.401 233.749 0)
			(layer "F.Fab")
			(hide yes)
			(effects
				(font
					(size 1 1)
					(thickness 0.15)
				)
			)
		)
		(property "MPN" "C1005X5R1E474M050BB"
			(at -46.401 233.749 0)
			(layer "F.Fab")
			(hide yes)
			(effects
				(font
					(size 1 1)
					(thickness 0.15)
				)
			)
		)
		(property "Manufacturer" "TDK"
			(at -46.401 233.749 0)
			(layer "F.Fab")
			(hide yes)
			(effects
				(font
					(size 1 1)
					(thickness 0.15)
				)
			)
		)
		(property "Val" "470n"
			(at -46.401 233.749 0)
			(layer "F.Fab")
			(hide yes)
			(effects
				(font
					(size 1 1)
					(thickness 0.15)
				)
			)
		)
		(property "Voltage" ""
			(at -46.401 233.749 0)
			(layer "F.Fab")
			(hide yes)
			(effects
				(font
					(size 1 1)
					(thickness 0.15)
				)
			)
		)
		(sheetname "/DDR3/")
		(sheetfile "ddr3.kicad_sch")
		(attr smd)
		(fp_rect
			(start -0.925 -0.47)
			(end 0.925 0.47)
			(stroke
				(width 0.05)
				(type default)
			)
			(fill no)
			(layer "F.CrtYd")
		)
		(fp_line
			(start -0.494 0.248)
			(end -0.494 -0.25)
			(stroke
				(width 0.15)
				(type solid)
			)
			(layer "F.Fab")
		)
		(fp_line
			(start 0.504 0.248)
			(end -0.494 0.248)
			(stroke
				(width 0.15)
				(type solid)
			)
			(layer "F.Fab")
		)
		(fp_line
			(start -0.494 -0.25)
			(end 0.504 -0.25)
			(stroke
				(width 0.15)
				(type solid)
			)
			(layer "F.Fab")
		)
		(fp_line
			(start 0.504 -0.25)
			(end 0.504 0.248)
			(stroke
				(width 0.15)
				(type solid)
			)
			(layer "F.Fab")
		)
		(pad "1" smd roundrect
			(at -0.48 0 270)
			(size 0.59 0.64)
			(layers "F.Cu" "F.Mask" "F.Paste")
			(roundrect_rratio 0.25)
			(net 1 "GND")
			(pintype "passive")
		)
		(pad "2" smd roundrect
			(at 0.48 0 270)
			(size 0.59 0.64)
			(layers "F.Cu" "F.Mask" "F.Paste")
			(roundrect_rratio 0.25)
			(net 3 "VCC1V35")
			(pintype "passive")
		)
	)
	(footprint "antmicro-footprints:C_0402_1005Metric"
		(layer "F.Cu")
		(at 93.374 154.675 90)
		(descr "Capacitor SMD 0402")
		(tags "capacitor SMD 0402")
		(property "Reference" "C51"
			(at -3.425 -7.774 90)
			(layer "F.SilkS")
			(effects
				(font
					(size 0.7 0.7)
					(thickness 0.15)
				)
				(justify left bottom)
			)
		)
		(property "Value" "C_470n_0402"
			(at 0 1.4 90)
			(layer "F.Fab")
			(effects
				(font
					(size 0.7 0.7)
					(thickness 0.15)
				)
				(justify left bottom)
			)
		)
		(property "Datasheet" "https://product.tdk.com/en/search/capacitor/ceramic/mlcc/info?part_no=C1005X5R1E474M050BB"
			(at 0 0 90)
			(layer "F.Fab")
			(hide yes)
			(effects
				(font
					(size 1.27 1.27)
					(thickness 0.15)
				)
			)
		)
		(property "Description" "SMD Multilayer Ceramic Capacitor, 0.47 µF, 25 V, 0402 [1005 Metric], ± 20%, X5R, C"
			(at 0 0 90)
			(layer "F.Fab")
			(hide yes)
			(effects
				(font
					(size 1.27 1.27)
					(thickness 0.15)
				)
			)
		)
		(property "Author" "Antmicro"
			(at 248.049 61.301 0)
			(layer "F.Fab")
			(hide yes)
			(effects
				(font
					(size 1 1)
					(thickness 0.15)
				)
			)
		)
		(property "Dielectric" ""
			(at 248.049 61.301 0)
			(layer "F.Fab")
			(hide yes)
			(effects
				(font
					(size 1 1)
					(thickness 0.15)
				)
			)
		)
		(property "License" "Apache-2.0"
			(at 248.049 61.301 0)
			(layer "F.Fab")
			(hide yes)
			(effects
				(font
					(size 1 1)
					(thickness 0.15)
				)
			)
		)
		(property "MPN" "C1005X5R1E474M050BB"
			(at 248.049 61.301 0)
			(layer "F.Fab")
			(hide yes)
			(effects
				(font
					(size 1 1)
					(thickness 0.15)
				)
			)
		)
		(property "Manufacturer" "TDK"
			(at 248.049 61.301 0)
			(layer "F.Fab")
			(hide yes)
			(effects
				(font
					(size 1 1)
					(thickness 0.15)
				)
			)
		)
		(property "Val" "470n"
			(at 248.049 61.301 0)
			(layer "F.Fab")
			(hide yes)
			(effects
				(font
					(size 1 1)
					(thickness 0.15)
				)
			)
		)
		(property "Voltage" ""
			(at 248.049 61.301 0)
			(layer "F.Fab")
			(hide yes)
			(effects
				(font
					(size 1 1)
					(thickness 0.15)
				)
			)
		)
		(sheetname "/DDR3/")
		(sheetfile "ddr3.kicad_sch")
		(attr smd)
		(fp_rect
			(start -0.925 -0.47)
			(end 0.925 0.47)
			(stroke
				(width 0.05)
				(type default)
			)
			(fill no)
			(layer "F.CrtYd")
		)
		(fp_line
			(start 0.504 -0.25)
			(end 0.504 0.248)
			(stroke
				(width 0.15)
				(type solid)
			)
			(layer "F.Fab")
		)
		(fp_line
			(start -0.494 -0.25)
			(end 0.504 -0.25)
			(stroke
				(width 0.15)
				(type solid)
			)
			(layer "F.Fab")
		)
		(fp_line
			(start 0.504 0.248)
			(end -0.494 0.248)
			(stroke
				(width 0.15)
				(type solid)
			)
			(layer "F.Fab")
		)
		(fp_line
			(start -0.494 0.248)
			(end -0.494 -0.25)
			(stroke
				(width 0.15)
				(type solid)
			)
			(layer "F.Fab")
		)
		(pad "1" smd roundrect
			(at -0.48 0 90)
			(size 0.59 0.64)
			(layers "F.Cu" "F.Mask" "F.Paste")
			(roundrect_rratio 0.25)
			(net 1 "GND")
			(pintype "passive")
		)
		(pad "2" smd roundrect
			(at 0.48 0 90)
			(size 0.59 0.64)
			(layers "F.Cu" "F.Mask" "F.Paste")
			(roundrect_rratio 0.25)
			(net 3 "VCC1V35")
			(pintype "passive")
		)
	)
	(footprint "antmicro-footprints:C_0402_1005Metric"
		(layer "F.Cu")
		(at 94.974 154.675 90)
		(descr "Capacitor SMD 0402")
		(tags "capacitor SMD 0402")
		(property "Reference" "C55"
			(at -3.425 -7.974 90)
			(layer "F.SilkS")
			(effects
				(font
					(size 0.7 0.7)
					(thickness 0.15)
				)
				(justify left bottom)
			)
		)
		(property "Value" "C_470n_0402"
			(at 0 1.4 90)
			(layer "F.Fab")
			(effects
				(font
					(size 0.7 0.7)
					(thickness 0.15)
				)
				(justify left bottom)
			)
		)
		(property "Datasheet" "https://product.tdk.com/en/search/capacitor/ceramic/mlcc/info?part_no=C1005X5R1E474M050BB"
			(at 0 0 90)
			(layer "F.Fab")
			(hide yes)
			(effects
				(font
					(size 1.27 1.27)
					(thickness 0.15)
				)
			)
		)
		(property "Description" "SMD Multilayer Ceramic Capacitor, 0.47 µF, 25 V, 0402 [1005 Metric], ± 20%, X5R, C"
			(at 0 0 90)
			(layer "F.Fab")
			(hide yes)
			(effects
				(font
					(size 1.27 1.27)
					(thickness 0.15)
				)
			)
		)
		(property "Author" "Antmicro"
			(at 249.649 59.701 0)
			(layer "F.Fab")
			(hide yes)
			(effects
				(font
					(size 1 1)
					(thickness 0.15)
				)
			)
		)
		(property "Dielectric" ""
			(at 249.649 59.701 0)
			(layer "F.Fab")
			(hide yes)
			(effects
				(font
					(size 1 1)
					(thickness 0.15)
				)
			)
		)
		(property "License" "Apache-2.0"
			(at 249.649 59.701 0)
			(layer "F.Fab")
			(hide yes)
			(effects
				(font
					(size 1 1)
					(thickness 0.15)
				)
			)
		)
		(property "MPN" "C1005X5R1E474M050BB"
			(at 249.649 59.701 0)
			(layer "F.Fab")
			(hide yes)
			(effects
				(font
					(size 1 1)
					(thickness 0.15)
				)
			)
		)
		(property "Manufacturer" "TDK"
			(at 249.649 59.701 0)
			(layer "F.Fab")
			(hide yes)
			(effects
				(font
					(size 1 1)
					(thickness 0.15)
				)
			)
		)
		(property "Val" "470n"
			(at 249.649 59.701 0)
			(layer "F.Fab")
			(hide yes)
			(effects
				(font
					(size 1 1)
					(thickness 0.15)
				)
			)
		)
		(property "Voltage" ""
			(at 249.649 59.701 0)
			(layer "F.Fab")
			(hide yes)
			(effects
				(font
					(size 1 1)
					(thickness 0.15)
				)
			)
		)
		(sheetname "/DDR3/")
		(sheetfile "ddr3.kicad_sch")
		(attr smd)
		(fp_rect
			(start -0.925 -0.47)
			(end 0.925 0.47)
			(stroke
				(width 0.05)
				(type default)
			)
			(fill no)
			(layer "F.CrtYd")
		)
		(fp_line
			(start 0.504 -0.25)
			(end 0.504 0.248)
			(stroke
				(width 0.15)
				(type solid)
			)
			(layer "F.Fab")
		)
		(fp_line
			(start -0.494 -0.25)
			(end 0.504 -0.25)
			(stroke
				(width 0.15)
				(type solid)
			)
			(layer "F.Fab")
		)
		(fp_line
			(start 0.504 0.248)
			(end -0.494 0.248)
			(stroke
				(width 0.15)
				(type solid)
			)
			(layer "F.Fab")
		)
		(fp_line
			(start -0.494 0.248)
			(end -0.494 -0.25)
			(stroke
				(width 0.15)
				(type solid)
			)
			(layer "F.Fab")
		)
		(pad "1" smd roundrect
			(at -0.48 0 90)
			(size 0.59 0.64)
			(layers "F.Cu" "F.Mask" "F.Paste")
			(roundrect_rratio 0.25)
			(net 1 "GND")
			(pintype "passive")
		)
		(pad "2" smd roundrect
			(at 0.48 0 90)
			(size 0.59 0.64)
			(layers "F.Cu" "F.Mask" "F.Paste")
			(roundrect_rratio 0.25)
			(net 3 "VCC1V35")
			(pintype "passive")
		)
	)
	(footprint "antmicro-footprints:C_0402_1005Metric"
		(layer "F.Cu")
		(at 101.774 154.675 90)
		(descr "Capacitor SMD 0402")
		(tags "capacitor SMD 0402")
		(property "Reference" "C50"
			(at -3.425 -8.174 90)
			(layer "F.SilkS")
			(effects
				(font
					(size 0.7 0.7)
					(thickness 0.15)
				)
				(justify left bottom)
			)
		)
		(property "Value" "C_470n_0402"
			(at 0 1.4 90)
			(layer "F.Fab")
			(effects
				(font
					(size 0.7 0.7)
					(thickness 0.15)
				)
				(justify left bottom)
			)
		)
		(property "Datasheet" "https://product.tdk.com/en/search/capacitor/ceramic/mlcc/info?part_no=C1005X5R1E474M050BB"
			(at 0 0 90)
			(layer "F.Fab")
			(hide yes)
			(effects
				(font
					(size 1.27 1.27)
					(thickness 0.15)
				)
			)
		)
		(property "Description" "SMD Multilayer Ceramic Capacitor, 0.47 µF, 25 V, 0402 [1005 Metric], ± 20%, X5R, C"
			(at 0 0 90)
			(layer "F.Fab")
			(hide yes)
			(effects
				(font
					(size 1.27 1.27)
					(thickness 0.15)
				)
			)
		)
		(property "Author" "Antmicro"
			(at 256.449 52.901 0)
			(layer "F.Fab")
			(hide yes)
			(effects
				(font
					(size 1 1)
					(thickness 0.15)
				)
			)
		)
		(property "Dielectric" ""
			(at 256.449 52.901 0)
			(layer "F.Fab")
			(hide yes)
			(effects
				(font
					(size 1 1)
					(thickness 0.15)
				)
			)
		)
		(property "License" "Apache-2.0"
			(at 256.449 52.901 0)
			(layer "F.Fab")
			(hide yes)
			(effects
				(font
					(size 1 1)
					(thickness 0.15)
				)
			)
		)
		(property "MPN" "C1005X5R1E474M050BB"
			(at 256.449 52.901 0)
			(layer "F.Fab")
			(hide yes)
			(effects
				(font
					(size 1 1)
					(thickness 0.15)
				)
			)
		)
		(property "Manufacturer" "TDK"
			(at 256.449 52.901 0)
			(layer "F.Fab")
			(hide yes)
			(effects
				(font
					(size 1 1)
					(thickness 0.15)
				)
			)
		)
		(property "Val" "470n"
			(at 256.449 52.901 0)
			(layer "F.Fab")
			(hide yes)
			(effects
				(font
					(size 1 1)
					(thickness 0.15)
				)
			)
		)
		(property "Voltage" ""
			(at 256.449 52.901 0)
			(layer "F.Fab")
			(hide yes)
			(effects
				(font
					(size 1 1)
					(thickness 0.15)
				)
			)
		)
		(sheetname "/DDR3/")
		(sheetfile "ddr3.kicad_sch")
		(attr smd)
		(fp_rect
			(start -0.925 -0.47)
			(end 0.925 0.47)
			(stroke
				(width 0.05)
				(type default)
			)
			(fill no)
			(layer "F.CrtYd")
		)
		(fp_line
			(start 0.504 -0.25)
			(end 0.504 0.248)
			(stroke
				(width 0.15)
				(type solid)
			)
			(layer "F.Fab")
		)
		(fp_line
			(start -0.494 -0.25)
			(end 0.504 -0.25)
			(stroke
				(width 0.15)
				(type solid)
			)
			(layer "F.Fab")
		)
		(fp_line
			(start 0.504 0.248)
			(end -0.494 0.248)
			(stroke
				(width 0.15)
				(type solid)
			)
			(layer "F.Fab")
		)
		(fp_line
			(start -0.494 0.248)
			(end -0.494 -0.25)
			(stroke
				(width 0.15)
				(type solid)
			)
			(layer "F.Fab")
		)
		(pad "1" smd roundrect
			(at -0.48 0 90)
			(size 0.59 0.64)
			(layers "F.Cu" "F.Mask" "F.Paste")
			(roundrect_rratio 0.25)
			(net 1 "GND")
			(pintype "passive")
		)
		(pad "2" smd roundrect
			(at 0.48 0 90)
			(size 0.59 0.64)
			(layers "F.Cu" "F.Mask" "F.Paste")
			(roundrect_rratio 0.25)
			(net 3 "VCC1V35")
			(pintype "passive")
		)
	)
	(footprint "antmicro-footprints:R_0402_1005Metric"
		(layer "F.Cu")
		(at 96.225 95.975 -90)
		(descr "Resistor SMD 0402")
		(tags "resistor SMD 0402")
		(property "Reference" "R157"
			(at 0.925 -0.375 90)
			(layer "F.SilkS")
			(effects
				(font
					(size 0.7 0.7)
					(thickness 0.15)
				)
				(justify right bottom)
			)
		)
		(property "Value" "R_10k2_0402"
			(at 0 1.4 90)
			(layer "F.Fab")
			(effects
				(font
					(size 0.7 0.7)
					(thickness 0.15)
				)
				(justify right bottom)
			)
		)
		(property "Datasheet" "https://www.bourns.com/docs/product-datasheets/cr.pdf"
			(at 0 0 270)
			(layer "F.Fab")
			(hide yes)
			(effects
				(font
					(size 1.27 1.27)
					(thickness 0.15)
				)
			)
		)
		(property "Description" "SMD Chip Resistor"
			(at 0 0 270)
			(layer "F.Fab")
			(hide yes)
			(effects
				(font
					(size 1.27 1.27)
					(thickness 0.15)
				)
			)
		)
		(property "Author" "Antmicro"
			(at 0.25 192.2 0)
			(layer "F.Fab")
			(hide yes)
			(effects
				(font
					(size 1 1)
					(thickness 0.15)
				)
			)
		)
		(property "License" "Apache-2.0"
			(at 0.25 192.2 0)
			(layer "F.Fab")
			(hide yes)
			(effects
				(font
					(size 1 1)
					(thickness 0.15)
				)
			)
		)
		(property "MPN" "CR0402-FX-1022GLF"
			(at 0.25 192.2 0)
			(layer "F.Fab")
			(hide yes)
			(effects
				(font
					(size 1 1)
					(thickness 0.15)
				)
			)
		)
		(property "Manufacturer" "Bourns"
			(at 0.25 192.2 0)
			(layer "F.Fab")
			(hide yes)
			(effects
				(font
					(size 1 1)
					(thickness 0.15)
				)
			)
		)
		(property "Tolerance" "1%"
			(at 0.25 192.2 0)
			(layer "F.Fab")
			(hide yes)
			(effects
				(font
					(size 1 1)
					(thickness 0.15)
				)
			)
		)
		(property "Val" "10k2"
			(at 0.25 192.2 0)
			(layer "F.Fab")
			(hide yes)
			(effects
				(font
					(size 1 1)
					(thickness 0.15)
				)
			)
		)
		(sheetname "/Ethernet/")
		(sheetfile "ethernet.kicad_sch")
		(attr smd)
		(fp_rect
			(start -0.925 -0.47)
			(end 0.925 0.47)
			(stroke
				(width 0.05)
				(type default)
			)
			(fill no)
			(layer "F.CrtYd")
		)
		(fp_rect
			(start -0.5 -0.25)
			(end 0.5 0.25)
			(stroke
				(width 0.15)
				(type solid)
			)
			(fill no)
			(layer "F.Fab")
		)
		(pad "1" smd roundrect
			(at -0.48 0 270)
			(size 0.59 0.64)
			(layers "F.Cu" "F.Mask" "F.Paste")
			(roundrect_rratio 0.25)
			(net 415 "/Ethernet/ETH_LED1")
			(pintype "passive")
		)
		(pad "2" smd roundrect
			(at 0.48 0 270)
			(size 0.59 0.64)
			(layers "F.Cu" "F.Mask" "F.Paste")
			(roundrect_rratio 0.25)
			(net 2 "VCC3V3")
			(pintype "passive")
		)
	)
	(footprint "antmicro-footprints:R_0402_1005Metric"
		(layer "F.Cu")
		(at 96.225 94.06 90)
		(descr "Resistor SMD 0402")
		(tags "resistor SMD 0402")
		(property "Reference" "R158"
			(at 0.86 0.375 90)
			(layer "F.SilkS")
			(effects
				(font
					(size 0.7 0.7)
					(thickness 0.15)
				)
				(justify left bottom)
			)
		)
		(property "Value" "R_10k2_0402"
			(at 0 1.4 90)
			(layer "F.Fab")
			(effects
				(font
					(size 0.7 0.7)
					(thickness 0.15)
				)
				(justify left bottom)
			)
		)
		(property "Datasheet" "https://www.bourns.com/docs/product-datasheets/cr.pdf"
			(at 0 0 90)
			(layer "F.Fab")
			(hide yes)
			(effects
				(font
					(size 1.27 1.27)
					(thickness 0.15)
				)
			)
		)
		(property "Description" "SMD Chip Resistor"
			(at 0 0 90)
			(layer "F.Fab")
			(hide yes)
			(effects
				(font
					(size 1.27 1.27)
					(thickness 0.15)
				)
			)
		)
		(property "Author" "Antmicro"
			(at 190.285 -2.165 0)
			(layer "F.Fab")
			(hide yes)
			(effects
				(font
					(size 1 1)
					(thickness 0.15)
				)
			)
		)
		(property "License" "Apache-2.0"
			(at 190.285 -2.165 0)
			(layer "F.Fab")
			(hide yes)
			(effects
				(font
					(size 1 1)
					(thickness 0.15)
				)
			)
		)
		(property "MPN" "CR0402-FX-1022GLF"
			(at 190.285 -2.165 0)
			(layer "F.Fab")
			(hide yes)
			(effects
				(font
					(size 1 1)
					(thickness 0.15)
				)
			)
		)
		(property "Manufacturer" "Bourns"
			(at 190.285 -2.165 0)
			(layer "F.Fab")
			(hide yes)
			(effects
				(font
					(size 1 1)
					(thickness 0.15)
				)
			)
		)
		(property "Tolerance" "1%"
			(at 190.285 -2.165 0)
			(layer "F.Fab")
			(hide yes)
			(effects
				(font
					(size 1 1)
					(thickness 0.15)
				)
			)
		)
		(property "Val" "10k2"
			(at 190.285 -2.165 0)
			(layer "F.Fab")
			(hide yes)
			(effects
				(font
					(size 1 1)
					(thickness 0.15)
				)
			)
		)
		(sheetname "/Ethernet/")
		(sheetfile "ethernet.kicad_sch")
		(attr smd)
		(fp_rect
			(start -0.925 -0.47)
			(end 0.925 0.47)
			(stroke
				(width 0.05)
				(type default)
			)
			(fill no)
			(layer "F.CrtYd")
		)
		(fp_rect
			(start -0.5 -0.25)
			(end 0.5 0.25)
			(stroke
				(width 0.15)
				(type solid)
			)
			(fill no)
			(layer "F.Fab")
		)
		(pad "1" smd roundrect
			(at -0.48 0 90)
			(size 0.59 0.64)
			(layers "F.Cu" "F.Mask" "F.Paste")
			(roundrect_rratio 0.25)
			(net 416 "/Ethernet/ETH_LED2")
			(pintype "passive")
		)
		(pad "2" smd roundrect
			(at 0.48 0 90)
			(size 0.59 0.64)
			(layers "F.Cu" "F.Mask" "F.Paste")
			(roundrect_rratio 0.25)
			(net 2 "VCC3V3")
			(pintype "passive")
		)
	)
)
